# S9S_MB_2U (Grand Teton) — schematic netlist excerpt (pin names and nets, part order shuffled) for the footprints in the layout excerpt that follows; sources: Cadence DE-HDL packaged netlist, KiCad conversion of 03242023_DA0F0TMBIJ0_F0T_Motherboard_J_brd_V01_OCP.brd

PR4233  Q_RES  0 5% CHIP  pkg 0402LF  page 278 : A = NC_PVCCD_HV_CPU0_ACSP5 ; B = GND
R945  Q_RES  10K 1% CHIP  pkg 0402LF  page 115 : A = P3V3_AUX ; B = PWRGD_FAIL_CPU1_CD_R1

(kicad_pcb
	(version 20260206)
	(generator "pcbnew")
	(generator_version "10.0")
	(general
		(thickness 1.6)
		(legacy_teardrops no)
	)
	(paper "A4")
	(title_block
		(title "03242023_DA0F0TMBIJ0_F0T_Motherboard_J_brd_V01_OCP.brd")
		(comment 1 "Grand Teton / footprints 5545-5546 of 6105")
	)
	(layers
		(0 "F.Cu" signal "TOP")
		(4 "In1.Cu" signal "GND")
		(6 "In2.Cu" signal "IN1")
		(8 "In3.Cu" signal "GND1")
		(10 "In4.Cu" signal "IN2")
		(12 "In5.Cu" signal "GND2")
		(14 "In6.Cu" signal "IN3")
		(16 "In7.Cu" signal "GND3")
		(18 "In8.Cu" signal "VCC")
		(20 "In9.Cu" signal "VCC1")
		(22 "In10.Cu" signal "GND4")
		(24 "In11.Cu" signal "IN4")
		(26 "In12.Cu" signal "GND5")
		(28 "In13.Cu" signal "IN5")
		(30 "In14.Cu" signal "GND6")
		(32 "In15.Cu" signal "IN6")
		(34 "In16.Cu" signal "GND7")
		(2 "B.Cu" signal "BOTTOM")
		(9 "F.Adhes" user "F.Adhesive")
		(11 "B.Adhes" user "B.Adhesive")
		(13 "F.Paste" user "Package Geometry/Pastemask Top")
		(15 "B.Paste" user "Package Geometry/Pastemask Bottom")
		(5 "F.SilkS" user "Ref Des/Silkscreen Top")
		(7 "B.SilkS" user "Ref Des/Silkscreen Bottom")
		(1 "F.Mask" user "Board Geometry/Soldermask Top")
		(3 "B.Mask" user "Board Geometry/Soldermask Bottom")
		(17 "Dwgs.User" user "User.Drawings")
		(19 "Cmts.User" user "User.Comments")
		(21 "Eco1.User" user "User.Eco1")
		(23 "Eco2.User" user "User.Eco2")
		(25 "Edge.Cuts" user "Board Geometry/Outline")
		(27 "Margin" user)
		(31 "F.CrtYd" user "Package Geometry/Place Bound Top")
		(29 "B.CrtYd" user "Package Geometry/Place Bound Bottom")
		(35 "F.Fab" user "Ref Des/Assembly Top")
		(33 "B.Fab" user "Ref Des/Assembly Bottom")
	)
	(footprint ""
		(layer "B.Cu")
		(at 37.947346 -318.252856)
		(property "Reference" "R945"
			(at 0 0 0)
			(layer "B.SilkS")
			(hide yes)
			(effects
				(font
					(size 1.27 1.27)
				)
				(justify mirror)
			)
		)
		(property "Value" ""
			(at 0 0 0)
			(layer "B.Fab")
			(effects
				(font
					(size 1.27 1.27)
				)
				(justify mirror)
			)
		)
		(duplicate_pad_numbers_are_jumpers no)
		(fp_line
			(start -0.7874 -0.4064)
			(end -0.7874 0.4064)
			(stroke
				(width 0.1524)
				(type default)
			)
			(layer "B.SilkS")
		)
		(fp_line
			(start -0.7874 0.4064)
			(end 0.7874 0.4064)
			(stroke
				(width 0.1524)
				(type default)
			)
			(layer "B.SilkS")
		)
		(fp_line
			(start 0.7874 -0.4064)
			(end -0.7874 -0.4064)
			(stroke
				(width 0.1524)
				(type default)
			)
			(layer "B.SilkS")
		)
		(fp_line
			(start 0.7874 0.4064)
			(end 0.7874 -0.4064)
			(stroke
				(width 0.1524)
				(type default)
			)
			(layer "B.SilkS")
		)
		(fp_line
			(start -0.67945 -0.3048)
			(end -0.67945 0.3048)
			(stroke
				(width 0.1)
				(type default)
			)
			(layer "B.Fab")
		)
		(fp_line
			(start -0.67945 0.3048)
			(end -0.120396 0.3048)
			(stroke
				(width 0.1)
				(type default)
			)
			(layer "B.Fab")
		)
		(fp_line
			(start -0.12065 -0.3048)
			(end -0.67945 -0.3048)
			(stroke
				(width 0.1)
				(type default)
			)
			(layer "B.Fab")
		)
		(fp_line
			(start -0.12065 -0.2794)
			(end -0.12065 -0.3048)
			(stroke
				(width 0.1)
				(type default)
			)
			(layer "B.Fab")
		)
		(fp_line
			(start -0.120396 0.2794)
			(end 0.12065 0.2794)
			(stroke
				(width 0.1)
				(type default)
			)
			(layer "B.Fab")
		)
		(fp_line
			(start -0.120396 0.3048)
			(end -0.120396 0.2794)
			(stroke
				(width 0.1)
				(type default)
			)
			(layer "B.Fab")
		)
		(fp_line
			(start 0.12065 -0.305054)
			(end 0.12065 -0.2794)
			(stroke
				(width 0.1)
				(type default)
			)
			(layer "B.Fab")
		)
		(fp_line
			(start 0.12065 -0.2794)
			(end -0.12065 -0.2794)
			(stroke
				(width 0.1)
				(type default)
			)
			(layer "B.Fab")
		)
		(fp_line
			(start 0.12065 0.2794)
			(end 0.12065 0.3048)
			(stroke
				(width 0.1)
				(type default)
			)
			(layer "B.Fab")
		)
		(fp_line
			(start 0.12065 0.3048)
			(end 0.67945 0.3048)
			(stroke
				(width 0.1)
				(type default)
			)
			(layer "B.Fab")
		)
		(fp_line
			(start 0.67945 -0.305054)
			(end 0.12065 -0.305054)
			(stroke
				(width 0.1)
				(type default)
			)
			(layer "B.Fab")
		)
		(fp_line
			(start 0.67945 0.3048)
			(end 0.67945 -0.305054)
			(stroke
				(width 0.1)
				(type default)
			)
			(layer "B.Fab")
		)
		(pad "1" smd circle
			(at 0.40005 0 180)
			(size 0 0)
			(layers "B.Cu" "B.Mask" "B.Paste")
			(net "P3V3_AUX")
		)
		(pad "2" smd circle
			(at -0.40005 0 180)
			(size 0 0)
			(layers "B.Cu" "B.Mask" "B.Paste")
			(net "PWRGD_FAIL_CPU1_CD_R1")
		)
	)
	(footprint ""
		(layer "B.Cu")
		(at 433.25288 -124.932948 90)
		(property "Reference" "PR4233"
			(at 0 0 90)
			(layer "B.SilkS")
			(hide yes)
			(effects
				(font
					(size 1.27 1.27)
				)
				(justify mirror)
			)
		)
		(property "Value" ""
			(at 0 0 90)
			(layer "B.Fab")
			(effects
				(font
					(size 1.27 1.27)
				)
				(justify mirror)
			)
		)
		(duplicate_pad_numbers_are_jumpers no)
		(fp_line
			(start 0.7874 -0.4064)
			(end -0.7874 -0.4064)
			(stroke
				(width 0.1524)
				(type default)
			)
			(layer "B.SilkS")
		)
		(fp_line
			(start -0.7874 -0.4064)
			(end -0.7874 0.4064)
			(stroke
				(width 0.1524)
				(type default)
			)
			(layer "B.SilkS")
		)
		(fp_line
			(start 0.7874 0.4064)
			(end 0.7874 -0.4064)
			(stroke
				(width 0.1524)
				(type default)
			)
			(layer "B.SilkS")
		)
		(fp_line
			(start -0.7874 0.4064)
			(end 0.7874 0.4064)
			(stroke
				(width 0.1524)
				(type default)
			)
			(layer "B.SilkS")
		)
		(fp_line
			(start 0.67945 -0.305054)
			(end 0.12065 -0.305054)
			(stroke
				(width 0.1)
				(type default)
			)
			(layer "B.Fab")
		)
		(fp_line
			(start 0.12065 -0.305054)
			(end 0.12065 -0.2794)
			(stroke
				(width 0.1)
				(type default)
			)
			(layer "B.Fab")
		)
		(fp_line
			(start -0.12065 -0.3048)
			(end -0.67945 -0.3048)
			(stroke
				(width 0.1)
				(type default)
			)
			(layer "B.Fab")
		)
		(fp_line
			(start -0.67945 -0.3048)
			(end -0.67945 0.3048)
			(stroke
				(width 0.1)
				(type default)
			)
			(layer "B.Fab")
		)
		(fp_line
			(start 0.12065 -0.2794)
			(end -0.12065 -0.2794)
			(stroke
				(width 0.1)
				(type default)
			)
			(layer "B.Fab")
		)
		(fp_line
			(start -0.12065 -0.2794)
			(end -0.12065 -0.3048)
			(stroke
				(width 0.1)
				(type default)
			)
			(layer "B.Fab")
		)
		(fp_line
			(start 0.12065 0.2794)
			(end 0.12065 0.3048)
			(stroke
				(width 0.1)
				(type default)
			)
			(layer "B.Fab")
		)
		(fp_line
			(start -0.120396 0.2794)
			(end 0.12065 0.2794)
			(stroke
				(width 0.1)
				(type default)
			)
			(layer "B.Fab")
		)
		(fp_line
			(start 0.67945 0.3048)
			(end 0.67945 -0.305054)
			(stroke
				(width 0.1)
				(type default)
			)
			(layer "B.Fab")
		)
		(fp_line
			(start 0.12065 0.3048)
			(end 0.67945 0.3048)
			(stroke
				(width 0.1)
				(type default)
			)
			(layer "B.Fab")
		)
		(fp_line
			(start -0.120396 0.3048)
			(end -0.120396 0.2794)
			(stroke
				(width 0.1)
				(type default)
			)
			(layer "B.Fab")
		)
		(fp_line
			(start -0.67945 0.3048)
			(end -0.120396 0.3048)
			(stroke
				(width 0.1)
				(type default)
			)
			(layer "B.Fab")
		)
		(pad "1" smd circle
			(at 0.40005 0 270)
			(size 0 0)
			(layers "B.Cu" "B.Mask" "B.Paste")
			(net "NC_PVCCD_HV_CPU0_ACSP5")
		)
		(pad "2" smd circle
			(at -0.40005 0 270)
			(size 0 0)
			(layers "B.Cu" "B.Mask" "B.Paste")
			(net "GND")
		)
	)
)
